(kicad_pcb
	(version 20260206)
	(generator "pcbnew")
	(generator_version "10.0")
	(general
		(thickness 1.6)
		(legacy_teardrops no)
	)
	(paper "A4")
	(title_block
		(title "04192023_DAF0TMB3IC0_F0TG_MB_C_brd_V02_OCP.brd")
		(comment 1 "Grand Teton / footprints 2523-2528 of 8354")
	)
	(layers
		(0 "F.Cu" signal "TOP")
		(4 "In1.Cu" signal "GND")
		(6 "In2.Cu" signal "IN1")
		(8 "In3.Cu" signal "GND1")
		(10 "In4.Cu" signal "IN2")
		(12 "In5.Cu" signal "GND2")
		(14 "In6.Cu" signal "IN3")
		(16 "In7.Cu" signal "GND3")
		(18 "In8.Cu" signal "VCC")
		(20 "In9.Cu" signal "VCC1")
		(22 "In10.Cu" signal "GND4")
		(24 "In11.Cu" signal "IN4")
		(26 "In12.Cu" signal "GND5")
		(28 "In13.Cu" signal "IN5")
		(30 "In14.Cu" signal "GND6")
		(32 "In15.Cu" signal "IN6")
		(34 "In16.Cu" signal "GND7")
		(2 "B.Cu" signal "BOTTOM")
		(9 "F.Adhes" user "F.Adhesive")
		(11 "B.Adhes" user "B.Adhesive")
		(13 "F.Paste" user "Package Geometry/Pastemask Top")
		(15 "B.Paste" user "Package Geometry/Pastemask Bottom")
		(5 "F.SilkS" user "Ref Des/Silkscreen Top")
		(7 "B.SilkS" user "Ref Des/Silkscreen Bottom")
		(1 "F.Mask" user "Board Geometry/Soldermask Top")
		(3 "B.Mask" user "Board Geometry/Soldermask Bottom")
		(17 "Dwgs.User" user "User.Drawings")
		(19 "Cmts.User" user "User.Comments")
		(21 "Eco1.User" user "User.Eco1")
		(23 "Eco2.User" user "User.Eco2")
		(25 "Edge.Cuts" user "Board Geometry/Outline")
		(27 "Margin" user)
		(31 "F.CrtYd" user "Package Geometry/Place Bound Top")
		(29 "B.CrtYd" user "Package Geometry/Place Bound Bottom")
		(35 "F.Fab" user "Ref Des/Assembly Top")
		(33 "B.Fab" user "Ref Des/Assembly Bottom")
	)
	(footprint ""
		(layer "F.Cu")
		(at 171.196 -104.993948 180)
		(property "Reference" "R169"
			(at 0 0 180)
			(layer "F.SilkS")
			(hide yes)
			(effects
				(font
					(size 1.27 1.27)
				)
			)
		)
		(property "Value" ""
			(at 0 0 180)
			(layer "F.Fab")
			(effects
				(font
					(size 1.27 1.27)
				)
			)
		)
		(duplicate_pad_numbers_are_jumpers no)
		(fp_line
			(start 0.7874 0.4064)
			(end -0.7874 0.4064)
			(stroke
				(width 0.1524)
				(type default)
			)
			(layer "F.SilkS")
		)
		(fp_line
			(start 0.7874 -0.4064)
			(end 0.7874 0.4064)
			(stroke
				(width 0.1524)
				(type default)
			)
			(layer "F.SilkS")
		)
		(fp_line
			(start -0.7874 0.4064)
			(end -0.7874 -0.4064)
			(stroke
				(width 0.1524)
				(type default)
			)
			(layer "F.SilkS")
		)
		(fp_line
			(start -0.7874 -0.4064)
			(end 0.7874 -0.4064)
			(stroke
				(width 0.1524)
				(type default)
			)
			(layer "F.SilkS")
		)
		(fp_line
			(start 0.67945 0.3048)
			(end 0.120396 0.3048)
			(stroke
				(width 0.1)
				(type default)
			)
			(layer "F.Fab")
		)
		(fp_line
			(start 0.67945 -0.3048)
			(end 0.67945 0.3048)
			(stroke
				(width 0.1)
				(type default)
			)
			(layer "F.Fab")
		)
		(fp_line
			(start 0.12065 -0.2794)
			(end 0.12065 -0.3048)
			(stroke
				(width 0.1)
				(type default)
			)
			(layer "F.Fab")
		)
		(fp_line
			(start 0.12065 -0.3048)
			(end 0.67945 -0.3048)
			(stroke
				(width 0.1)
				(type default)
			)
			(layer "F.Fab")
		)
		(fp_line
			(start 0.120396 0.3048)
			(end 0.120396 0.2794)
			(stroke
				(width 0.1)
				(type default)
			)
			(layer "F.Fab")
		)
		(fp_line
			(start 0.120396 0.2794)
			(end -0.12065 0.2794)
			(stroke
				(width 0.1)
				(type default)
			)
			(layer "F.Fab")
		)
		(fp_line
			(start -0.12065 0.3048)
			(end -0.67945 0.3048)
			(stroke
				(width 0.1)
				(type default)
			)
			(layer "F.Fab")
		)
		(fp_line
			(start -0.12065 0.2794)
			(end -0.12065 0.3048)
			(stroke
				(width 0.1)
				(type default)
			)
			(layer "F.Fab")
		)
		(fp_line
			(start -0.12065 -0.2794)
			(end 0.12065 -0.2794)
			(stroke
				(width 0.1)
				(type default)
			)
			(layer "F.Fab")
		)
		(fp_line
			(start -0.12065 -0.305054)
			(end -0.12065 -0.2794)
			(stroke
				(width 0.1)
				(type default)
			)
			(layer "F.Fab")
		)
		(fp_line
			(start -0.67945 0.3048)
			(end -0.67945 -0.305054)
			(stroke
				(width 0.1)
				(type default)
			)
			(layer "F.Fab")
		)
		(fp_line
			(start -0.67945 -0.305054)
			(end -0.12065 -0.305054)
			(stroke
				(width 0.1)
				(type default)
			)
			(layer "F.Fab")
		)
		(pad "1" smd circle
			(at -0.40005 0 180)
			(size 0 0)
			(layers "F.Cu" "F.Mask" "F.Paste")
			(net "FM_I3C_CPU1_MUX0_OE_R_N")
		)
		(pad "2" smd circle
			(at 0.40005 0 180)
			(size 0 0)
			(layers "F.Cu" "F.Mask" "F.Paste")
			(net "FM_I3C_CPU1_MUX0_OE_N")
		)
	)
	(footprint ""
		(layer "F.Cu")
		(at 120.396 -433.451)
		(property "Reference" "R3497"
			(at 0 0 0)
			(layer "F.SilkS")
			(hide yes)
			(effects
				(font
					(size 1.27 1.27)
				)
			)
		)
		(property "Value" ""
			(at 0 0 0)
			(layer "F.Fab")
			(effects
				(font
					(size 1.27 1.27)
				)
			)
		)
		(duplicate_pad_numbers_are_jumpers no)
		(fp_line
			(start -0.7874 -0.4064)
			(end 0.7874 -0.4064)
			(stroke
				(width 0.1524)
				(type default)
			)
			(layer "F.SilkS")
		)
		(fp_line
			(start -0.7874 0.4064)
			(end -0.7874 -0.4064)
			(stroke
				(width 0.1524)
				(type default)
			)
			(layer "F.SilkS")
		)
		(fp_line
			(start 0.7874 -0.4064)
			(end 0.7874 0.4064)
			(stroke
				(width 0.1524)
				(type default)
			)
			(layer "F.SilkS")
		)
		(fp_line
			(start 0.7874 0.4064)
			(end -0.7874 0.4064)
			(stroke
				(width 0.1524)
				(type default)
			)
			(layer "F.SilkS")
		)
		(fp_line
			(start -0.67945 -0.305054)
			(end -0.12065 -0.305054)
			(stroke
				(width 0.1)
				(type default)
			)
			(layer "F.Fab")
		)
		(fp_line
			(start -0.67945 0.3048)
			(end -0.67945 -0.305054)
			(stroke
				(width 0.1)
				(type default)
			)
			(layer "F.Fab")
		)
		(fp_line
			(start -0.12065 -0.305054)
			(end -0.12065 -0.2794)
			(stroke
				(width 0.1)
				(type default)
			)
			(layer "F.Fab")
		)
		(fp_line
			(start -0.12065 -0.2794)
			(end 0.12065 -0.2794)
			(stroke
				(width 0.1)
				(type default)
			)
			(layer "F.Fab")
		)
		(fp_line
			(start -0.12065 0.2794)
			(end -0.12065 0.3048)
			(stroke
				(width 0.1)
				(type default)
			)
			(layer "F.Fab")
		)
		(fp_line
			(start -0.12065 0.3048)
			(end -0.67945 0.3048)
			(stroke
				(width 0.1)
				(type default)
			)
			(layer "F.Fab")
		)
		(fp_line
			(start 0.120396 0.2794)
			(end -0.12065 0.2794)
			(stroke
				(width 0.1)
				(type default)
			)
			(layer "F.Fab")
		)
		(fp_line
			(start 0.120396 0.3048)
			(end 0.120396 0.2794)
			(stroke
				(width 0.1)
				(type default)
			)
			(layer "F.Fab")
		)
		(fp_line
			(start 0.12065 -0.3048)
			(end 0.67945 -0.3048)
			(stroke
				(width 0.1)
				(type default)
			)
			(layer "F.Fab")
		)
		(fp_line
			(start 0.12065 -0.2794)
			(end 0.12065 -0.3048)
			(stroke
				(width 0.1)
				(type default)
			)
			(layer "F.Fab")
		)
		(fp_line
			(start 0.67945 -0.3048)
			(end 0.67945 0.3048)
			(stroke
				(width 0.1)
				(type default)
			)
			(layer "F.Fab")
		)
		(fp_line
			(start 0.67945 0.3048)
			(end 0.120396 0.3048)
			(stroke
				(width 0.1)
				(type default)
			)
			(layer "F.Fab")
		)
		(pad "1" smd circle
			(at -0.40005 0)
			(size 0 0)
			(layers "F.Cu" "F.Mask" "F.Paste")
			(net "GPU_FPGA_EROT_RECOV_BUF_R_N")
		)
		(pad "2" smd circle
			(at 0.40005 0)
			(size 0 0)
			(layers "F.Cu" "F.Mask" "F.Paste")
			(net "GPU_FPGA_EROT_RECOV_BUF_N")
		)
	)
	(footprint ""
		(layer "F.Cu")
		(at 148.73859 -98.755708 90)
		(property "Reference" "R3308"
			(at 0 0 90)
			(layer "F.SilkS")
			(hide yes)
			(effects
				(font
					(size 1.27 1.27)
				)
			)
		)
		(property "Value" ""
			(at 0 0 90)
			(layer "F.Fab")
			(effects
				(font
					(size 1.27 1.27)
				)
			)
		)
		(duplicate_pad_numbers_are_jumpers no)
		(fp_line
			(start 0.7874 -0.4064)
			(end 0.7874 0.4064)
			(stroke
				(width 0.1524)
				(type default)
			)
			(layer "F.SilkS")
		)
		(fp_line
			(start -0.7874 -0.4064)
			(end 0.7874 -0.4064)
			(stroke
				(width 0.1524)
				(type default)
			)
			(layer "F.SilkS")
		)
		(fp_line
			(start 0.7874 0.4064)
			(end -0.7874 0.4064)
			(stroke
				(width 0.1524)
				(type default)
			)
			(layer "F.SilkS")
		)
		(fp_line
			(start -0.7874 0.4064)
			(end -0.7874 -0.4064)
			(stroke
				(width 0.1524)
				(type default)
			)
			(layer "F.SilkS")
		)
		(fp_line
			(start -0.12065 -0.305054)
			(end -0.12065 -0.2794)
			(stroke
				(width 0.1)
				(type default)
			)
			(layer "F.Fab")
		)
		(fp_line
			(start -0.67945 -0.305054)
			(end -0.12065 -0.305054)
			(stroke
				(width 0.1)
				(type default)
			)
			(layer "F.Fab")
		)
		(fp_line
			(start 0.67945 -0.3048)
			(end 0.67945 0.3048)
			(stroke
				(width 0.1)
				(type default)
			)
			(layer "F.Fab")
		)
		(fp_line
			(start 0.12065 -0.3048)
			(end 0.67945 -0.3048)
			(stroke
				(width 0.1)
				(type default)
			)
			(layer "F.Fab")
		)
		(fp_line
			(start 0.12065 -0.2794)
			(end 0.12065 -0.3048)
			(stroke
				(width 0.1)
				(type default)
			)
			(layer "F.Fab")
		)
		(fp_line
			(start -0.12065 -0.2794)
			(end 0.12065 -0.2794)
			(stroke
				(width 0.1)
				(type default)
			)
			(layer "F.Fab")
		)
		(fp_line
			(start 0.120396 0.2794)
			(end -0.12065 0.2794)
			(stroke
				(width 0.1)
				(type default)
			)
			(layer "F.Fab")
		)
		(fp_line
			(start -0.12065 0.2794)
			(end -0.12065 0.3048)
			(stroke
				(width 0.1)
				(type default)
			)
			(layer "F.Fab")
		)
		(fp_line
			(start 0.67945 0.3048)
			(end 0.120396 0.3048)
			(stroke
				(width 0.1)
				(type default)
			)
			(layer "F.Fab")
		)
		(fp_line
			(start 0.120396 0.3048)
			(end 0.120396 0.2794)
			(stroke
				(width 0.1)
				(type default)
			)
			(layer "F.Fab")
		)
		(fp_line
			(start -0.12065 0.3048)
			(end -0.67945 0.3048)
			(stroke
				(width 0.1)
				(type default)
			)
			(layer "F.Fab")
		)
		(fp_line
			(start -0.67945 0.3048)
			(end -0.67945 -0.305054)
			(stroke
				(width 0.1)
				(type default)
			)
			(layer "F.Fab")
		)
		(pad "1" smd circle
			(at -0.40005 0 90)
			(size 0 0)
			(layers "F.Cu" "F.Mask" "F.Paste")
			(net "OCP_V3_2_PRSNT_ALL_R_N")
		)
		(pad "2" smd circle
			(at 0.40005 0 90)
			(size 0 0)
			(layers "F.Cu" "F.Mask" "F.Paste")
			(net "OCP_V3_2_PRSNT_ALL_R1_N")
		)
	)
	(footprint ""
		(layer "F.Cu")
		(at 191.246506 -342.487758 -90)
		(property "Reference" "PL55"
			(at -15.522956 3.048254 0)
			(unlocked yes)
			(layer "F.SilkS")
			(effects
				(font
					(size 0.7874 0.5842)
					(thickness 0.1524)
				)
				(justify left)
			)
		)
		(property "Value" ""
			(at 0 0 270)
			(layer "F.Fab")
			(effects
				(font
					(size 1.27 1.27)
				)
			)
		)
		(duplicate_pad_numbers_are_jumpers no)
		(fp_line
			(start -4.99999 3.849878)
			(end -4.99999 2.23901)
			(stroke
				(width 0.1524)
				(type default)
			)
			(layer "F.SilkS")
		)
		(fp_line
			(start 4.99999 3.849878)
			(end -4.99999 3.849878)
			(stroke
				(width 0.1524)
				(type default)
			)
			(layer "F.SilkS")
		)
		(fp_line
			(start 4.99999 2.23901)
			(end 4.99999 3.849878)
			(stroke
				(width 0.1524)
				(type default)
			)
			(layer "F.SilkS")
		)
		(fp_line
			(start -4.99999 -2.23901)
			(end -4.99999 -3.849878)
			(stroke
				(width 0.1524)
				(type default)
			)
			(layer "F.SilkS")
		)
		(fp_line
			(start -4.99999 -3.849878)
			(end 4.99999 -3.849878)
			(stroke
				(width 0.1524)
				(type default)
			)
			(layer "F.SilkS")
		)
		(fp_line
			(start 4.99999 -3.849878)
			(end 4.99999 -2.23901)
			(stroke
				(width 0.1524)
				(type default)
			)
			(layer "F.SilkS")
		)
		(fp_line
			(start -4.99999 3.849878)
			(end -4.99999 -3.849878)
			(stroke
				(width 0.1)
				(type default)
			)
			(layer "F.Fab")
		)
		(fp_line
			(start 4.99999 3.849878)
			(end -4.99999 3.849878)
			(stroke
				(width 0.1)
				(type default)
			)
			(layer "F.Fab")
		)
		(fp_line
			(start -4.99999 -3.849878)
			(end 4.99999 -3.849878)
			(stroke
				(width 0.1)
				(type default)
			)
			(layer "F.Fab")
		)
		(fp_line
			(start 4.99999 -3.849878)
			(end 4.99999 3.849878)
			(stroke
				(width 0.1)
				(type default)
			)
			(layer "F.Fab")
		)
		(pad "1" smd rect
			(at -3.299968 0 270)
			(size 3.302 4.2164)
			(layers "F.Cu" "F.Mask" "F.Paste")
			(net "SW_PVDD11_S3_P1_SW2")
		)
		(pad "2" smd rect
			(at 3.299968 0 270)
			(size 3.302 4.2164)
			(layers "F.Cu" "F.Mask" "F.Paste")
			(net "PVDD11_S3_P1")
		)
	)
	(footprint ""
		(layer "F.Cu")
		(at 316.738 -359.283 180)
		(property "Reference" "R8075"
			(at 0 0 180)
			(layer "F.SilkS")
			(hide yes)
			(effects
				(font
					(size 1.27 1.27)
				)
			)
		)
		(property "Value" ""
			(at 0 0 180)
			(layer "F.Fab")
			(effects
				(font
					(size 1.27 1.27)
				)
			)
		)
		(duplicate_pad_numbers_are_jumpers no)
		(fp_line
			(start 0.7874 0.4064)
			(end -0.7874 0.4064)
			(stroke
				(width 0.1524)
				(type default)
			)
			(layer "F.SilkS")
		)
		(fp_line
			(start 0.7874 -0.4064)
			(end 0.7874 0.4064)
			(stroke
				(width 0.1524)
				(type default)
			)
			(layer "F.SilkS")
		)
		(fp_line
			(start -0.7874 0.4064)
			(end -0.7874 -0.4064)
			(stroke
				(width 0.1524)
				(type default)
			)
			(layer "F.SilkS")
		)
		(fp_line
			(start -0.7874 -0.4064)
			(end 0.7874 -0.4064)
			(stroke
				(width 0.1524)
				(type default)
			)
			(layer "F.SilkS")
		)
		(fp_line
			(start 0.67945 0.3048)
			(end 0.120396 0.3048)
			(stroke
				(width 0.1)
				(type default)
			)
			(layer "F.Fab")
		)
		(fp_line
			(start 0.67945 -0.3048)
			(end 0.67945 0.3048)
			(stroke
				(width 0.1)
				(type default)
			)
			(layer "F.Fab")
		)
		(fp_line
			(start 0.12065 -0.2794)
			(end 0.12065 -0.3048)
			(stroke
				(width 0.1)
				(type default)
			)
			(layer "F.Fab")
		)
		(fp_line
			(start 0.12065 -0.3048)
			(end 0.67945 -0.3048)
			(stroke
				(width 0.1)
				(type default)
			)
			(layer "F.Fab")
		)
		(fp_line
			(start 0.120396 0.3048)
			(end 0.120396 0.2794)
			(stroke
				(width 0.1)
				(type default)
			)
			(layer "F.Fab")
		)
		(fp_line
			(start 0.120396 0.2794)
			(end -0.12065 0.2794)
			(stroke
				(width 0.1)
				(type default)
			)
			(layer "F.Fab")
		)
		(fp_line
			(start -0.12065 0.3048)
			(end -0.67945 0.3048)
			(stroke
				(width 0.1)
				(type default)
			)
			(layer "F.Fab")
		)
		(fp_line
			(start -0.12065 0.2794)
			(end -0.12065 0.3048)
			(stroke
				(width 0.1)
				(type default)
			)
			(layer "F.Fab")
		)
		(fp_line
			(start -0.12065 -0.2794)
			(end 0.12065 -0.2794)
			(stroke
				(width 0.1)
				(type default)
			)
			(layer "F.Fab")
		)
		(fp_line
			(start -0.12065 -0.305054)
			(end -0.12065 -0.2794)
			(stroke
				(width 0.1)
				(type default)
			)
			(layer "F.Fab")
		)
		(fp_line
			(start -0.67945 0.3048)
			(end -0.67945 -0.305054)
			(stroke
				(width 0.1)
				(type default)
			)
			(layer "F.Fab")
		)
		(fp_line
			(start -0.67945 -0.305054)
			(end -0.12065 -0.305054)
			(stroke
				(width 0.1)
				(type default)
			)
			(layer "F.Fab")
		)
		(pad "1" smd circle
			(at -0.40005 0 180)
			(size 0 0)
			(layers "F.Cu" "F.Mask" "F.Paste")
			(net "PVDD18_S5_P0")
		)
		(pad "2" smd circle
			(at 0.40005 0 180)
			(size 0 0)
			(layers "F.Cu" "F.Mask" "F.Paste")
			(net "PVDDCR_CPU1_P0_OCP_N_R")
		)
	)
	(footprint ""
		(layer "F.Cu")
		(at 119.379238 -41.17975 -90)
		(property "Reference" "R6280"
			(at 0 0 270)
			(layer "F.SilkS")
			(hide yes)
			(effects
				(font
					(size 1.27 1.27)
				)
			)
		)
		(property "Value" ""
			(at 0 0 270)
			(layer "F.Fab")
			(effects
				(font
					(size 1.27 1.27)
				)
			)
		)
		(duplicate_pad_numbers_are_jumpers no)
		(fp_line
			(start -0.7874 0.4064)
			(end -0.7874 -0.4064)
			(stroke
				(width 0.1524)
				(type default)
			)
			(layer "F.SilkS")
		)
		(fp_line
			(start 0.7874 0.4064)
			(end -0.7874 0.4064)
			(stroke
				(width 0.1524)
				(type default)
			)
			(layer "F.SilkS")
		)
		(fp_line
			(start -0.7874 -0.4064)
			(end 0.7874 -0.4064)
			(stroke
				(width 0.1524)
				(type default)
			)
			(layer "F.SilkS")
		)
		(fp_line
			(start 0.7874 -0.4064)
			(end 0.7874 0.4064)
			(stroke
				(width 0.1524)
				(type default)
			)
			(layer "F.SilkS")
		)
		(fp_line
			(start -0.67945 0.3048)
			(end -0.67945 -0.305054)
			(stroke
				(width 0.1)
				(type default)
			)
			(layer "F.Fab")
		)
		(fp_line
			(start -0.12065 0.3048)
			(end -0.67945 0.3048)
			(stroke
				(width 0.1)
				(type default)
			)
			(layer "F.Fab")
		)
		(fp_line
			(start 0.120396 0.3048)
			(end 0.120396 0.2794)
			(stroke
				(width 0.1)
				(type default)
			)
			(layer "F.Fab")
		)
		(fp_line
			(start 0.67945 0.3048)
			(end 0.120396 0.3048)
			(stroke
				(width 0.1)
				(type default)
			)
			(layer "F.Fab")
		)
		(fp_line
			(start -0.12065 0.2794)
			(end -0.12065 0.3048)
			(stroke
				(width 0.1)
				(type default)
			)
			(layer "F.Fab")
		)
		(fp_line
			(start 0.120396 0.2794)
			(end -0.12065 0.2794)
			(stroke
				(width 0.1)
				(type default)
			)
			(layer "F.Fab")
		)
		(fp_line
			(start -0.12065 -0.2794)
			(end 0.12065 -0.2794)
			(stroke
				(width 0.1)
				(type default)
			)
			(layer "F.Fab")
		)
		(fp_line
			(start 0.12065 -0.2794)
			(end 0.12065 -0.3048)
			(stroke
				(width 0.1)
				(type default)
			)
			(layer "F.Fab")
		)
		(fp_line
			(start 0.12065 -0.3048)
			(end 0.67945 -0.3048)
			(stroke
				(width 0.1)
				(type default)
			)
			(layer "F.Fab")
		)
		(fp_line
			(start 0.67945 -0.3048)
			(end 0.67945 0.3048)
			(stroke
				(width 0.1)
				(type default)
			)
			(layer "F.Fab")
		)
		(fp_line
			(start -0.67945 -0.305054)
			(end -0.12065 -0.305054)
			(stroke
				(width 0.1)
				(type default)
			)
			(layer "F.Fab")
		)
		(fp_line
			(start -0.12065 -0.305054)
			(end -0.12065 -0.2794)
			(stroke
				(width 0.1)
				(type default)
			)
			(layer "F.Fab")
		)
		(pad "1" smd circle
			(at -0.40005 0 270)
			(size 0 0)
			(layers "F.Cu" "F.Mask" "F.Paste")
			(net "SMB_USB_CPU0_HUB1_SCL")
		)
		(pad "2" smd circle
			(at 0.40005 0 270)
			(size 0 0)
			(layers "F.Cu" "F.Mask" "F.Paste")
			(net "SMB_USB_HUB2_TI_SCL_MRP_PRT_CTL1")
		)
	)
)
